(kicad_pcb
	(version 20260206)
	(generator "pcbnew")
	(generator_version "10.0")
	(general
		(thickness 1.6)
		(legacy_teardrops no)
	)
	(paper "A4")
	(title_block
		(title "Bryce Canyon_F.DPB_16315-1-OCP.brd")
		(comment 1 "Bryce Canyon / footprints 1343-1351 of 2223")
	)
	(layers
		(0 "F.Cu" signal "TOP")
		(4 "In1.Cu" signal "L2GND")
		(6 "In2.Cu" signal "L3")
		(8 "In3.Cu" signal "L4GND")
		(10 "In4.Cu" signal "L5")
		(12 "In5.Cu" signal "L6VCC")
		(14 "In6.Cu" signal "L7VCC")
		(16 "In7.Cu" signal "L8")
		(18 "In8.Cu" signal "L9GND")
		(20 "In9.Cu" signal "L10")
		(22 "In10.Cu" signal "L11GND")
		(2 "B.Cu" signal "BOTTOM")
		(9 "F.Adhes" user "F.Adhesive")
		(11 "B.Adhes" user "B.Adhesive")
		(13 "F.Paste" user "Package Geometry/Pastemask Top")
		(15 "B.Paste" user "Package Geometry/Pastemask Bottom")
		(5 "F.SilkS" user "Ref Des/Silkscreen Top")
		(7 "B.SilkS" user "Ref Des/Silkscreen Bottom")
		(1 "F.Mask" user "Board Geometry/Soldermask Top")
		(3 "B.Mask" user "Board Geometry/Soldermask Bottom")
		(17 "Dwgs.User" user "User.Drawings")
		(19 "Cmts.User" user "User.Comments")
		(21 "Eco1.User" user "User.Eco1")
		(23 "Eco2.User" user "User.Eco2")
		(25 "Edge.Cuts" user "Board Geometry/Outline")
		(27 "Margin" user)
		(31 "F.CrtYd" user "Package Geometry/Place Bound Top")
		(29 "B.CrtYd" user "Package Geometry/Place Bound Bottom")
		(35 "F.Fab" user "Ref Des/Assembly Top")
		(33 "B.Fab" user "Ref Des/Assembly Bottom")
	)
	(footprint ""
		(layer "F.Cu")
		(at 95.563436 -273.660616 90)
		(property "Reference" "C65"
			(at 0 0 90)
			(layer "F.SilkS")
			(hide yes)
			(effects
				(font
					(size 1.27 1.27)
				)
			)
		)
		(property "Value" "SCD01U16V1KX-GP"
			(at -2.8321 -1.7399 90)
			(unlocked yes)
			(layer "F.Fab")
			(hide yes)
			(effects
				(font
					(size 1.016 1.016)
					(thickness 0.1524)
				)
			)
		)
		(property "Device Type" "C0201H13"
			(at -2.8321 -3.2639 90)
			(unlocked yes)
			(layer "F.Fab")
			(hide yes)
			(effects
				(font
					(size 1.016 1.016)
					(thickness 0.1524)
				)
			)
		)
		(duplicate_pad_numbers_are_jumpers no)
		(fp_rect
			(start -0.2794 0.6477)
			(end 0.2794 -0.6477)
			(stroke
				(width 0)
				(type default)
			)
			(fill no)
			(layer "F.CrtYd")
		)
		(fp_rect
			(start -0.2794 0.6477)
			(end 0.2794 -0.6477)
			(stroke
				(width 0)
				(type default)
			)
			(fill no)
			(layer "F.Fab")
		)
		(pad "1" smd custom
			(at 0 -0.2794 90)
			(size 0.0762 0.0762)
			(layers "F.Cu" "F.Mask" "F.Paste")
			(net "SAS_HDD_RX_P2")
			(options
				(clearance outline)
				(anchor circle)
			)
			(primitives
				(gr_poly
					(pts
						(arc
							(start 0.1524 -0.127)
							(mid 0.137521 -0.162921)
							(end 0.1016 -0.1778)
						)
						(arc
							(start -0.1016 -0.1778)
							(mid -0.137521 -0.162921)
							(end -0.1524 -0.127)
						)
						(arc
							(start -0.1524 0.127)
							(mid -0.137521 0.162921)
							(end -0.1016 0.1778)
						)
						(arc
							(start 0.1016 0.1778)
							(mid 0.137521 0.162921)
							(end 0.1524 0.127)
						)
					)
					(width 0)
					(fill yes)
				)
			)
		)
		(pad "2" smd custom
			(at 0 0.2794 90)
			(size 0.0762 0.0762)
			(layers "F.Cu" "F.Mask" "F.Paste")
			(net "PHY_SCC_A_TO_DRV_A_2_DP")
			(options
				(clearance outline)
				(anchor circle)
			)
			(primitives
				(gr_poly
					(pts
						(arc
							(start 0.1524 -0.127)
							(mid 0.137521 -0.162921)
							(end 0.1016 -0.1778)
						)
						(arc
							(start -0.1016 -0.1778)
							(mid -0.137521 -0.162921)
							(end -0.1524 -0.127)
						)
						(arc
							(start -0.1524 0.127)
							(mid -0.137521 0.162921)
							(end -0.1016 0.1778)
						)
						(arc
							(start 0.1016 0.1778)
							(mid 0.137521 0.162921)
							(end 0.1524 0.127)
						)
					)
					(width 0)
					(fill yes)
				)
			)
		)
	)
	(footprint ""
		(layer "F.Cu")
		(at 101.765862 -300.992794 90)
		(property "Reference" "R569"
			(at 0 0 90)
			(layer "F.SilkS")
			(hide yes)
			(effects
				(font
					(size 1.27 1.27)
				)
			)
		)
		(property "Value" "4K7R2J-2-GP"
			(at 0.064008 -3.993896 90)
			(unlocked yes)
			(layer "F.Fab")
			(hide yes)
			(effects
				(font
					(size 1.016 1.016)
					(thickness 0.1524)
				)
			)
		)
		(property "Device Type" "R402H16"
			(at 0.064008 -5.517896 90)
			(unlocked yes)
			(layer "F.Fab")
			(hide yes)
			(effects
				(font
					(size 1.016 1.016)
					(thickness 0.1524)
				)
			)
		)
		(duplicate_pad_numbers_are_jumpers no)
		(fp_line
			(start 0.508 -0.9398)
			(end -0.508 -0.9398)
			(stroke
				(width 0.1524)
				(type default)
			)
			(layer "F.SilkS")
		)
		(fp_line
			(start -0.508 -0.9398)
			(end -0.508 0.9398)
			(stroke
				(width 0.1524)
				(type default)
			)
			(layer "F.SilkS")
		)
		(fp_rect
			(start -0.508 0.9398)
			(end 0.508 -0.9398)
			(stroke
				(width 0)
				(type default)
			)
			(fill no)
			(layer "F.CrtYd")
		)
		(fp_rect
			(start -0.508 0.9398)
			(end 0.508 -0.9398)
			(stroke
				(width 0)
				(type default)
			)
			(fill no)
			(layer "F.Fab")
		)
		(pad "1" smd custom
			(at 0 -0.4445 90)
			(size 0.1397 0.1397)
			(layers "F.Cu" "F.Mask" "F.Paste")
			(net "DRIVE_B_27_FLT_LED")
			(options
				(clearance outline)
				(anchor circle)
			)
			(primitives
				(gr_poly
					(pts
						(arc
							(start -0.1778 -0.2794)
							(mid -0.249642 -0.249642)
							(end -0.2794 -0.1778)
						)
						(arc
							(start -0.2794 0.1778)
							(mid -0.249642 0.249642)
							(end -0.1778 0.2794)
						)
						(arc
							(start 0.1778 0.2794)
							(mid 0.249642 0.249642)
							(end 0.2794 0.1778)
						)
						(arc
							(start 0.2794 -0.1778)
							(mid 0.249642 -0.249642)
							(end 0.1778 -0.2794)
						)
					)
					(width 0)
					(fill yes)
				)
			)
		)
		(pad "2" smd custom
			(at 0 0.4445 90)
			(size 0.1397 0.1397)
			(layers "F.Cu" "F.Mask" "F.Paste")
			(net "GND")
			(options
				(clearance outline)
				(anchor circle)
			)
			(primitives
				(gr_poly
					(pts
						(arc
							(start -0.1778 -0.2794)
							(mid -0.249642 -0.249642)
							(end -0.2794 -0.1778)
						)
						(arc
							(start -0.2794 0.1778)
							(mid -0.249642 0.249642)
							(end -0.1778 0.2794)
						)
						(arc
							(start 0.1778 0.2794)
							(mid 0.249642 0.249642)
							(end 0.2794 0.1778)
						)
						(arc
							(start 0.2794 -0.1778)
							(mid 0.249642 -0.249642)
							(end 0.1778 -0.2794)
						)
					)
					(width 0)
					(fill yes)
				)
			)
		)
	)
	(footprint ""
		(layer "F.Cu")
		(at 181.483 -292.270942)
		(property "Reference" "R244"
			(at 0 0 0)
			(layer "F.SilkS")
			(hide yes)
			(effects
				(font
					(size 1.27 1.27)
				)
			)
		)
		(property "Value" "2R6F-GP"
			(at -0.0508 -4.8514 0)
			(unlocked yes)
			(layer "F.Fab")
			(hide yes)
			(effects
				(font
					(size 1.016 1.016)
					(thickness 0.1524)
				)
			)
		)
		(property "Device Type" "R1206H26"
			(at 0 -6.3754 0)
			(unlocked yes)
			(layer "F.Fab")
			(hide yes)
			(effects
				(font
					(size 1.016 1.016)
					(thickness 0.1524)
				)
			)
		)
		(duplicate_pad_numbers_are_jumpers no)
		(fp_line
			(start -1.016 -2.2352)
			(end 1.016 -2.2352)
			(stroke
				(width 0.1524)
				(type default)
			)
			(layer "F.SilkS")
		)
		(fp_line
			(start -1.016 2.2352)
			(end -1.016 -2.2352)
			(stroke
				(width 0.1524)
				(type default)
			)
			(layer "F.SilkS")
		)
		(fp_line
			(start 1.016 -2.2352)
			(end 1.016 2.2352)
			(stroke
				(width 0.1524)
				(type default)
			)
			(layer "F.SilkS")
		)
		(fp_line
			(start 1.016 2.2352)
			(end -1.016 2.2352)
			(stroke
				(width 0.1524)
				(type default)
			)
			(layer "F.SilkS")
		)
		(fp_rect
			(start -1.0922 2.3114)
			(end 1.0922 -2.3114)
			(stroke
				(width 0)
				(type default)
			)
			(fill no)
			(layer "F.CrtYd")
		)
		(fp_poly
			(pts
				(xy -1.0922 -2.3114) (xy 1.0922 -2.3114) (xy 1.0922 2.3114) (xy -1.0922 2.3114)
			)
			(stroke
				(width 0)
				(type default)
			)
			(fill no)
			(layer "F.Fab")
		)
		(pad "1" smd rect
			(at 0 -1.397)
			(size 1.651 1.27)
			(layers "F.Cu" "F.Mask" "F.Paste")
			(net "P5V_HDD5")
		)
		(pad "2" smd rect
			(at 0 1.397)
			(size 1.651 1.27)
			(layers "F.Cu" "F.Mask" "F.Paste")
			(net "5V_PRE_5")
		)
	)
	(footprint ""
		(layer "F.Cu")
		(at 338.074 -49.443894 90)
		(property "Reference" "R836"
			(at 0 0 90)
			(layer "F.SilkS")
			(hide yes)
			(effects
				(font
					(size 1.27 1.27)
				)
			)
		)
		(property "Value" "200KR2F-L-GP"
			(at 0.064008 -3.993896 90)
			(unlocked yes)
			(layer "F.Fab")
			(hide yes)
			(effects
				(font
					(size 1.016 1.016)
					(thickness 0.1524)
				)
			)
		)
		(property "Device Type" "R402H16"
			(at 0.064008 -5.517896 90)
			(unlocked yes)
			(layer "F.Fab")
			(hide yes)
			(effects
				(font
					(size 1.016 1.016)
					(thickness 0.1524)
				)
			)
		)
		(duplicate_pad_numbers_are_jumpers no)
		(fp_line
			(start 0.508 -0.9398)
			(end -0.508 -0.9398)
			(stroke
				(width 0.1524)
				(type default)
			)
			(layer "F.SilkS")
		)
		(fp_line
			(start -0.508 -0.9398)
			(end -0.508 0.9398)
			(stroke
				(width 0.1524)
				(type default)
			)
			(layer "F.SilkS")
		)
		(fp_rect
			(start -0.508 0.9398)
			(end 0.508 -0.9398)
			(stroke
				(width 0)
				(type default)
			)
			(fill no)
			(layer "F.CrtYd")
		)
		(fp_rect
			(start -0.508 0.9398)
			(end 0.508 -0.9398)
			(stroke
				(width 0)
				(type default)
			)
			(fill no)
			(layer "F.Fab")
		)
		(pad "1" smd custom
			(at 0 -0.4445 90)
			(size 0.1397 0.1397)
			(layers "F.Cu" "F.Mask" "F.Paste")
			(net "SW_HDD_R30")
			(options
				(clearance outline)
				(anchor circle)
			)
			(primitives
				(gr_poly
					(pts
						(arc
							(start -0.1778 -0.2794)
							(mid -0.249642 -0.249642)
							(end -0.2794 -0.1778)
						)
						(arc
							(start -0.2794 0.1778)
							(mid -0.249642 0.249642)
							(end -0.1778 0.2794)
						)
						(arc
							(start 0.1778 0.2794)
							(mid 0.249642 0.249642)
							(end 0.2794 0.1778)
						)
						(arc
							(start 0.2794 -0.1778)
							(mid 0.249642 -0.249642)
							(end 0.1778 -0.2794)
						)
					)
					(width 0)
					(fill yes)
				)
			)
		)
		(pad "2" smd custom
			(at 0 0.4445 90)
			(size 0.1397 0.1397)
			(layers "F.Cu" "F.Mask" "F.Paste")
			(net "SW_HDD_N30")
			(options
				(clearance outline)
				(anchor circle)
			)
			(primitives
				(gr_poly
					(pts
						(arc
							(start -0.1778 -0.2794)
							(mid -0.249642 -0.249642)
							(end -0.2794 -0.1778)
						)
						(arc
							(start -0.2794 0.1778)
							(mid -0.249642 0.249642)
							(end -0.1778 0.2794)
						)
						(arc
							(start 0.1778 0.2794)
							(mid 0.249642 0.249642)
							(end 0.2794 0.1778)
						)
						(arc
							(start 0.2794 -0.1778)
							(mid 0.249642 -0.249642)
							(end 0.1778 -0.2794)
						)
					)
					(width 0)
					(fill yes)
				)
			)
		)
	)
	(footprint ""
		(layer "F.Cu")
		(at 51.980846 -62.778894 -90)
		(property "Reference" "C365"
			(at 0 0 270)
			(layer "F.SilkS")
			(hide yes)
			(effects
				(font
					(size 1.27 1.27)
				)
			)
		)
		(property "Value" "SC1U16V3KX-5GP"
			(at 0 -2.8194 270)
			(unlocked yes)
			(layer "F.Fab")
			(hide yes)
			(effects
				(font
					(size 1.016 1.016)
					(thickness 0.1524)
				)
			)
		)
		(property "Device Type" "C603H36"
			(at 0 -4.3434 270)
			(unlocked yes)
			(layer "F.Fab")
			(hide yes)
			(effects
				(font
					(size 1.016 1.016)
					(thickness 0.1524)
				)
			)
		)
		(duplicate_pad_numbers_are_jumpers no)
		(fp_line
			(start 0.508 0)
			(end -0.508 0)
			(stroke
				(width 0.2032)
				(type default)
			)
			(layer "F.SilkS")
		)
		(fp_rect
			(start -0.5842 1.3335)
			(end 0.5842 -1.3335)
			(stroke
				(width 0)
				(type default)
			)
			(fill no)
			(layer "F.CrtYd")
		)
		(fp_rect
			(start -0.5842 1.3335)
			(end 0.5842 -1.3335)
			(stroke
				(width 0)
				(type default)
			)
			(fill no)
			(layer "F.Fab")
		)
		(pad "1" smd custom
			(at 0 -0.762 270)
			(size 0.2159 0.2159)
			(layers "F.Cu" "F.Mask" "F.Paste")
			(net "P5V_HDD25")
			(options
				(clearance outline)
				(anchor circle)
			)
			(primitives
				(gr_poly
					(pts
						(arc
							(start -0.3302 -0.4318)
							(mid -0.402042 -0.402042)
							(end -0.4318 -0.3302)
						)
						(arc
							(start -0.4318 0.3302)
							(mid -0.402042 0.402042)
							(end -0.3302 0.4318)
						)
						(arc
							(start 0.3302 0.4318)
							(mid 0.402042 0.402042)
							(end 0.4318 0.3302)
						)
						(arc
							(start 0.4318 -0.3302)
							(mid 0.402042 -0.402042)
							(end 0.3302 -0.4318)
						)
					)
					(width 0)
					(fill yes)
				)
			)
		)
		(pad "2" smd custom
			(at 0 0.762 270)
			(size 0.2159 0.2159)
			(layers "F.Cu" "F.Mask" "F.Paste")
			(net "GND")
			(options
				(clearance outline)
				(anchor circle)
			)
			(primitives
				(gr_poly
					(pts
						(arc
							(start -0.3302 -0.4318)
							(mid -0.402042 -0.402042)
							(end -0.4318 -0.3302)
						)
						(arc
							(start -0.4318 0.3302)
							(mid -0.402042 0.402042)
							(end -0.3302 0.4318)
						)
						(arc
							(start 0.3302 0.4318)
							(mid 0.402042 0.402042)
							(end 0.4318 0.3302)
						)
						(arc
							(start 0.4318 -0.3302)
							(mid 0.402042 -0.402042)
							(end 0.3302 -0.4318)
						)
					)
					(width 0)
					(fill yes)
				)
			)
		)
	)
	(footprint ""
		(layer "F.Cu")
		(at 363.020102 -303.954942 180)
		(property "Reference" "C135"
			(at 0 0 180)
			(layer "F.SilkS")
			(hide yes)
			(effects
				(font
					(size 1.27 1.27)
				)
			)
		)
		(property "Value" "SC4D7U25V5KX-1-GP"
			(at -0.0762 -6.1214 180)
			(unlocked yes)
			(layer "F.Fab")
			(hide yes)
			(effects
				(font
					(size 1.016 1.016)
					(thickness 0.1524)
				)
			)
		)
		(property "Device Type" "C805H58"
			(at -0.0762 -8.1534 180)
			(unlocked yes)
			(layer "F.Fab")
			(hide yes)
			(effects
				(font
					(size 1.016 1.016)
					(thickness 0.1524)
				)
			)
		)
		(duplicate_pad_numbers_are_jumpers no)
		(fp_line
			(start 0.635 0)
			(end -0.635 0)
			(stroke
				(width 0.508)
				(type default)
			)
			(layer "F.SilkS")
		)
		(fp_rect
			(start -0.9652 1.778)
			(end 0.9652 -1.778)
			(stroke
				(width 0)
				(type default)
			)
			(fill no)
			(layer "F.CrtYd")
		)
		(fp_poly
			(pts
				(xy -0.9652 -1.778) (xy 0.9652 -1.778) (xy 0.9652 1.778) (xy -0.9652 1.778)
			)
			(stroke
				(width 0)
				(type default)
			)
			(fill no)
			(layer "F.Fab")
		)
		(pad "1" smd rect
			(at 0 -0.9652 180)
			(size 1.397 1.143)
			(layers "F.Cu" "F.Mask" "F.Paste")
			(net "P12V_HDD7")
		)
		(pad "2" smd rect
			(at 0 0.9652 180)
			(size 1.397 1.143)
			(layers "F.Cu" "F.Mask" "F.Paste")
			(net "GND")
		)
	)
	(footprint ""
		(layer "F.Cu")
		(at 149.932898 -292.270942)
		(property "Reference" "R221"
			(at 0 0 0)
			(layer "F.SilkS")
			(hide yes)
			(effects
				(font
					(size 1.27 1.27)
				)
			)
		)
		(property "Value" "2R6F-GP"
			(at -0.0508 -4.8514 0)
			(unlocked yes)
			(layer "F.Fab")
			(hide yes)
			(effects
				(font
					(size 1.016 1.016)
					(thickness 0.1524)
				)
			)
		)
		(property "Device Type" "R1206H26"
			(at 0 -6.3754 0)
			(unlocked yes)
			(layer "F.Fab")
			(hide yes)
			(effects
				(font
					(size 1.016 1.016)
					(thickness 0.1524)
				)
			)
		)
		(duplicate_pad_numbers_are_jumpers no)
		(fp_line
			(start -1.016 -2.2352)
			(end 1.016 -2.2352)
			(stroke
				(width 0.1524)
				(type default)
			)
			(layer "F.SilkS")
		)
		(fp_line
			(start -1.016 2.2352)
			(end -1.016 -2.2352)
			(stroke
				(width 0.1524)
				(type default)
			)
			(layer "F.SilkS")
		)
		(fp_line
			(start 1.016 -2.2352)
			(end 1.016 2.2352)
			(stroke
				(width 0.1524)
				(type default)
			)
			(layer "F.SilkS")
		)
		(fp_line
			(start 1.016 2.2352)
			(end -1.016 2.2352)
			(stroke
				(width 0.1524)
				(type default)
			)
			(layer "F.SilkS")
		)
		(fp_rect
			(start -1.0922 2.3114)
			(end 1.0922 -2.3114)
			(stroke
				(width 0)
				(type default)
			)
			(fill no)
			(layer "F.CrtYd")
		)
		(fp_poly
			(pts
				(xy -1.0922 -2.3114) (xy 1.0922 -2.3114) (xy 1.0922 2.3114) (xy -1.0922 2.3114)
			)
			(stroke
				(width 0)
				(type default)
			)
			(fill no)
			(layer "F.Fab")
		)
		(pad "1" smd rect
			(at 0 -1.397)
			(size 1.651 1.27)
			(layers "F.Cu" "F.Mask" "F.Paste")
			(net "P5V_HDD4")
		)
		(pad "2" smd rect
			(at 0 1.397)
			(size 1.651 1.27)
			(layers "F.Cu" "F.Mask" "F.Paste")
			(net "5V_PRE_4")
		)
	)
	(footprint ""
		(layer "F.Cu")
		(at 459.801722 -299.435012 -90)
		(property "Reference" "R363"
			(at 0 0 270)
			(layer "F.SilkS")
			(hide yes)
			(effects
				(font
					(size 1.27 1.27)
				)
			)
		)
		(property "Value" "2R6F-GP"
			(at -0.0508 -4.8514 270)
			(unlocked yes)
			(layer "F.Fab")
			(hide yes)
			(effects
				(font
					(size 1.016 1.016)
					(thickness 0.1524)
				)
			)
		)
		(property "Device Type" "R1206H26"
			(at 0 -6.3754 270)
			(unlocked yes)
			(layer "F.Fab")
			(hide yes)
			(effects
				(font
					(size 1.016 1.016)
					(thickness 0.1524)
				)
			)
		)
		(duplicate_pad_numbers_are_jumpers no)
		(fp_line
			(start -1.016 2.2352)
			(end -1.016 -2.2352)
			(stroke
				(width 0.1524)
				(type default)
			)
			(layer "F.SilkS")
		)
		(fp_line
			(start 1.016 2.2352)
			(end -1.016 2.2352)
			(stroke
				(width 0.1524)
				(type default)
			)
			(layer "F.SilkS")
		)
		(fp_line
			(start -1.016 -2.2352)
			(end 1.016 -2.2352)
			(stroke
				(width 0.1524)
				(type default)
			)
			(layer "F.SilkS")
		)
		(fp_line
			(start 1.016 -2.2352)
			(end 1.016 2.2352)
			(stroke
				(width 0.1524)
				(type default)
			)
			(layer "F.SilkS")
		)
		(fp_rect
			(start -1.0922 2.3114)
			(end 1.0922 -2.3114)
			(stroke
				(width 0)
				(type default)
			)
			(fill no)
			(layer "F.CrtYd")
		)
		(fp_poly
			(pts
				(xy -1.0922 -2.3114) (xy 1.0922 -2.3114) (xy 1.0922 2.3114) (xy -1.0922 2.3114)
			)
			(stroke
				(width 0)
				(type default)
			)
			(fill no)
			(layer "F.Fab")
		)
		(pad "1" smd rect
			(at 0 -1.397 270)
			(size 1.651 1.27)
			(layers "F.Cu" "F.Mask" "F.Paste")
			(net "P12V_HDD10")
		)
		(pad "2" smd rect
			(at 0 1.397 270)
			(size 1.651 1.27)
			(layers "F.Cu" "F.Mask" "F.Paste")
			(net "12V_PRE_10")
		)
	)
	(footprint ""
		(layer "F.Cu")
		(at 109.365796 -64.683894 -90)
		(property "Reference" "C395"
			(at 0 0 270)
			(layer "F.SilkS")
			(hide yes)
			(effects
				(font
					(size 1.27 1.27)
				)
			)
		)
		(property "Value" "SC4D7U25V5KX-1-GP"
			(at -0.0762 -6.1214 270)
			(unlocked yes)
			(layer "F.Fab")
			(hide yes)
			(effects
				(font
					(size 1.016 1.016)
					(thickness 0.1524)
				)
			)
		)
		(property "Device Type" "C805H58"
			(at -0.0762 -8.1534 270)
			(unlocked yes)
			(layer "F.Fab")
			(hide yes)
			(effects
				(font
					(size 1.016 1.016)
					(thickness 0.1524)
				)
			)
		)
		(duplicate_pad_numbers_are_jumpers no)
		(fp_line
			(start 0.635 0)
			(end -0.635 0)
			(stroke
				(width 0.508)
				(type default)
			)
			(layer "F.SilkS")
		)
		(fp_rect
			(start -0.9652 1.778)
			(end 0.9652 -1.778)
			(stroke
				(width 0)
				(type default)
			)
			(fill no)
			(layer "F.CrtYd")
		)
		(fp_poly
			(pts
				(xy -0.9652 -1.778) (xy 0.9652 -1.778) (xy 0.9652 1.778) (xy -0.9652 1.778)
			)
			(stroke
				(width 0)
				(type default)
			)
			(fill no)
			(layer "F.Fab")
		)
		(pad "1" smd rect
			(at 0 -0.9652 270)
			(size 1.397 1.143)
			(layers "F.Cu" "F.Mask" "F.Paste")
			(net "P12V_HDD27")
		)
		(pad "2" smd rect
			(at 0 0.9652 270)
			(size 1.397 1.143)
			(layers "F.Cu" "F.Mask" "F.Paste")
			(net "GND")
		)
	)
)
